(kicad_pcb
	(version 20260206)
	(generator "pcbnew")
	(generator_version "10.0")
	(general
		(thickness 1.6)
		(legacy_teardrops no)
	)
	(paper "A4")
	(title_block
		(title "peb — Lightning_PEB_BRD.brd")
		(comment 1 "Lightning (Wiwynn / Facebook NVMe JBOF) / footprint 1585 of 2563 (U40), pads 228-346 of 408")
	)
	(layers
		(0 "F.Cu" signal "TOP")
		(4 "In1.Cu" signal "L2GND")
		(6 "In2.Cu" signal "L3")
		(8 "In3.Cu" signal "L4VCC")
		(10 "In4.Cu" signal "L5VCC")
		(12 "In5.Cu" signal "L6")
		(14 "In6.Cu" signal "L7GND")
		(2 "B.Cu" signal "BOTTOM")
		(9 "F.Adhes" user "F.Adhesive")
		(11 "B.Adhes" user "B.Adhesive")
		(13 "F.Paste" user "Package Geometry/Pastemask Top")
		(15 "B.Paste" user "Package Geometry/Pastemask Bottom")
		(5 "F.SilkS" user "Ref Des/Silkscreen Top")
		(7 "B.SilkS" user "Ref Des/Silkscreen Bottom")
		(1 "F.Mask" user "Board Geometry/Soldermask Top")
		(3 "B.Mask" user "Board Geometry/Soldermask Bottom")
		(17 "Dwgs.User" user "User.Drawings")
		(19 "Cmts.User" user "User.Comments")
		(21 "Eco1.User" user "User.Eco1")
		(23 "Eco2.User" user "User.Eco2")
		(25 "Edge.Cuts" user "Board Geometry/Outline")
		(27 "Margin" user)
		(31 "F.CrtYd" user "Package Geometry/Place Bound Top")
		(29 "B.CrtYd" user "Package Geometry/Place Bound Bottom")
		(35 "F.Fab" user "Ref Des/Assembly Top")
		(33 "B.Fab" user "Ref Des/Assembly Bottom")
	)
	(footprint ""
		(layer "F.Cu")
		(at 38.104826 -130.48488 180)
		(property "Reference" "U40"
			(at 0 0 180)
			(layer "F.SilkS")
			(hide yes)
			(effects
				(font
					(size 1.27 1.27)
				)
			)
		)
		(property "Value" "AST2400A1-GP"
			(at -17.7292 -6.184392 180)
			(unlocked yes)
			(layer "F.Fab")
			(hide yes)
			(effects
				(font
					(size 1.016 1.016)
					(thickness 0.1524)
				)
			)
		)
		(property "Device Type" "BGA408D19H52"
			(at -17.7292 -7.708392 180)
			(unlocked yes)
			(layer "F.Fab")
			(hide yes)
			(effects
				(font
					(size 1.016 1.016)
					(thickness 0.1524)
				)
			)
		)
		(duplicate_pad_numbers_are_jumpers no)
		(pad "K20" smd circle
			(at 6.800088 -1.199896 180)
			(size 0.3556 0.3556)
			(layers "F.Cu" "F.Mask" "F.Paste")
			(net "TP_GPIOY3")
		)
		(pad "K21" smd circle
			(at 7.599934 -1.199896 180)
			(size 0.3556 0.3556)
			(layers "F.Cu" "F.Mask" "F.Paste")
			(net "BMC0_SMB1_CLK")
		)
		(pad "K22" smd circle
			(at 8.400034 -1.199896 180)
			(size 0.3556 0.3556)
			(layers "F.Cu" "F.Mask" "F.Paste")
			(net "BMC0_SMB1_DAT")
		)
		(pad "L1" smd circle
			(at -8.400034 -0.40005 180)
			(size 0.3556 0.3556)
			(layers "F.Cu" "F.Mask" "F.Paste")
			(net "ADC_P1V53_BMC")
		)
		(pad "L2" smd circle
			(at -7.599934 -0.40005 180)
			(size 0.3556 0.3556)
			(layers "F.Cu" "F.Mask" "F.Paste")
			(net "ADC_P1V8_STBY_BMC")
		)
		(pad "L3" smd circle
			(at -6.800088 -0.40005 180)
			(size 0.3556 0.3556)
			(layers "F.Cu" "F.Mask" "F.Paste")
			(net "ADC_P3V3_STBY_BMC")
		)
		(pad "L4" smd circle
			(at -5.999988 -0.40005 180)
			(size 0.3556 0.3556)
			(layers "F.Cu" "F.Mask" "F.Paste")
			(net "ADC_P5V_STBY_BMC")
		)
		(pad "L5" smd circle
			(at -5.199888 -0.40005 180)
			(size 0.3556 0.3556)
			(layers "F.Cu" "F.Mask" "F.Paste")
			(net "ADC0_12V_BMC")
		)
		(pad "L6" smd circle
			(at -4.400042 -0.40005 180)
			(size 0.3556 0.3556)
			(layers "F.Cu" "F.Mask" "F.Paste")
			(net "P1V26_STBY")
		)
		(pad "L9" smd circle
			(at -1.999996 -0.40005 180)
			(size 0.3556 0.3556)
			(layers "F.Cu" "F.Mask" "F.Paste")
			(net "GND")
		)
		(pad "L10" smd circle
			(at -1.199896 -0.40005 180)
			(size 0.3556 0.3556)
			(layers "F.Cu" "F.Mask" "F.Paste")
			(net "GND")
		)
		(pad "L11" smd circle
			(at -0.40005 -0.40005 180)
			(size 0.3556 0.3556)
			(layers "F.Cu" "F.Mask" "F.Paste")
			(net "GND")
		)
		(pad "L12" smd circle
			(at 0.40005 -0.40005 180)
			(size 0.3556 0.3556)
			(layers "F.Cu" "F.Mask" "F.Paste")
			(net "GND")
		)
		(pad "L13" smd circle
			(at 1.199896 -0.40005 180)
			(size 0.3556 0.3556)
			(layers "F.Cu" "F.Mask" "F.Paste")
			(net "GND")
		)
		(pad "L14" smd circle
			(at 1.999996 -0.40005 180)
			(size 0.3556 0.3556)
			(layers "F.Cu" "F.Mask" "F.Paste")
			(net "GND")
		)
		(pad "L17" smd circle
			(at 4.400042 -0.40005 180)
			(size 0.3556 0.3556)
			(layers "F.Cu" "F.Mask" "F.Paste")
			(net "P1V26_STBY")
		)
		(pad "L18" smd circle
			(at 5.199888 -0.40005 180)
			(size 0.3556 0.3556)
			(layers "F.Cu" "F.Mask" "F.Paste")
			(net "ROMA12")
		)
		(pad "L19" smd circle
			(at 5.999988 -0.40005 180)
			(size 0.3556 0.3556)
			(layers "F.Cu" "F.Mask" "F.Paste")
			(net "ROMA13")
		)
		(pad "L20" smd circle
			(at 6.800088 -0.40005 180)
			(size 0.3556 0.3556)
			(layers "F.Cu" "F.Mask" "F.Paste")
			(net "ROMA14")
		)
		(pad "L21" smd circle
			(at 7.599934 -0.40005 180)
			(size 0.3556 0.3556)
			(layers "F.Cu" "F.Mask" "F.Paste")
			(net "ROMA15")
		)
		(pad "L22" smd circle
			(at 8.400034 -0.40005 180)
			(size 0.3556 0.3556)
			(layers "F.Cu" "F.Mask" "F.Paste")
			(net "ROMA22")
		)
		(pad "M1" smd circle
			(at -8.400034 0.40005 180)
			(size 0.3556 0.3556)
			(layers "F.Cu" "F.Mask" "F.Paste")
			(net "GND")
		)
		(pad "M2" smd circle
			(at -7.599934 0.40005 180)
			(size 0.3556 0.3556)
			(layers "F.Cu" "F.Mask" "F.Paste")
			(net "GND")
		)
		(pad "M3" smd circle
			(at -6.800088 0.40005 180)
			(size 0.3556 0.3556)
			(layers "F.Cu" "F.Mask" "F.Paste")
			(net "ADC_P1V26_BMC")
		)
		(pad "M4" smd circle
			(at -5.999988 0.40005 180)
			(size 0.3556 0.3556)
			(layers "F.Cu" "F.Mask" "F.Paste")
			(net "ADC_P0V9_E_BMC")
		)
		(pad "M5" smd circle
			(at -5.199888 0.40005 180)
			(size 0.3556 0.3556)
			(layers "F.Cu" "F.Mask" "F.Paste")
			(net "ADC_P0V9_BMC")
		)
		(pad "M6" smd circle
			(at -4.400042 0.40005 180)
			(size 0.3556 0.3556)
			(layers "F.Cu" "F.Mask" "F.Paste")
			(net "P3V3_STBY")
		)
		(pad "M9" smd circle
			(at -1.999996 0.40005 180)
			(size 0.3556 0.3556)
			(layers "F.Cu" "F.Mask" "F.Paste")
			(net "GND")
		)
		(pad "M10" smd circle
			(at -1.199896 0.40005 180)
			(size 0.3556 0.3556)
			(layers "F.Cu" "F.Mask" "F.Paste")
			(net "GND")
		)
		(pad "M11" smd circle
			(at -0.40005 0.40005 180)
			(size 0.3556 0.3556)
			(layers "F.Cu" "F.Mask" "F.Paste")
			(net "GND")
		)
		(pad "M12" smd circle
			(at 0.40005 0.40005 180)
			(size 0.3556 0.3556)
			(layers "F.Cu" "F.Mask" "F.Paste")
			(net "GND")
		)
		(pad "M13" smd circle
			(at 1.199896 0.40005 180)
			(size 0.3556 0.3556)
			(layers "F.Cu" "F.Mask" "F.Paste")
			(net "GND")
		)
		(pad "M14" smd circle
			(at 1.999996 0.40005 180)
			(size 0.3556 0.3556)
			(layers "F.Cu" "F.Mask" "F.Paste")
			(net "GND")
		)
		(pad "M17" smd circle
			(at 4.400042 0.40005 180)
			(size 0.3556 0.3556)
			(layers "F.Cu" "F.Mask" "F.Paste")
			(net "P3V3_STBY")
		)
		(pad "M18" smd circle
			(at 5.199888 0.40005 180)
			(size 0.3556 0.3556)
			(layers "F.Cu" "F.Mask" "F.Paste")
			(net "ROMA19")
		)
		(pad "M19" smd circle
			(at 5.999988 0.40005 180)
			(size 0.3556 0.3556)
			(layers "F.Cu" "F.Mask" "F.Paste")
			(net "ROMA8")
		)
		(pad "M20" smd circle
			(at 6.800088 0.40005 180)
			(size 0.3556 0.3556)
			(layers "F.Cu" "F.Mask" "F.Paste")
			(net "ROMA9")
		)
		(pad "M21" smd circle
			(at 7.599934 0.40005 180)
			(size 0.3556 0.3556)
			(layers "F.Cu" "F.Mask" "F.Paste")
			(net "ROMA10")
		)
		(pad "M22" smd circle
			(at 8.400034 0.40005 180)
			(size 0.3556 0.3556)
			(layers "F.Cu" "F.Mask" "F.Paste")
			(net "ROMA11")
		)
		(pad "N1" smd circle
			(at -8.400034 1.199896 180)
			(size 0.3556 0.3556)
			(layers "F.Cu" "F.Mask" "F.Paste")
			(net "GND")
		)
		(pad "N2" smd circle
			(at -7.599934 1.199896 180)
			(size 0.3556 0.3556)
			(layers "F.Cu" "F.Mask" "F.Paste")
			(net "GND")
		)
		(pad "N3" smd circle
			(at -6.800088 1.199896 180)
			(size 0.3556 0.3556)
			(layers "F.Cu" "F.Mask" "F.Paste")
			(net "GND")
		)
		(pad "N4" smd circle
			(at -5.999988 1.199896 180)
			(size 0.3556 0.3556)
			(layers "F.Cu" "F.Mask" "F.Paste")
			(net "GND")
		)
		(pad "N5" smd circle
			(at -5.199888 1.199896 180)
			(size 0.3556 0.3556)
			(layers "F.Cu" "F.Mask" "F.Paste")
			(net "GND")
		)
		(pad "N6" smd circle
			(at -4.400042 1.199896 180)
			(size 0.3556 0.3556)
			(layers "F.Cu" "F.Mask" "F.Paste")
			(net "P3V3_STBY")
		)
		(pad "N9" smd circle
			(at -1.999996 1.199896 180)
			(size 0.3556 0.3556)
			(layers "F.Cu" "F.Mask" "F.Paste")
			(net "GND")
		)
		(pad "N10" smd circle
			(at -1.199896 1.199896 180)
			(size 0.3556 0.3556)
			(layers "F.Cu" "F.Mask" "F.Paste")
			(net "GND")
		)
		(pad "N11" smd circle
			(at -0.40005 1.199896 180)
			(size 0.3556 0.3556)
			(layers "F.Cu" "F.Mask" "F.Paste")
			(net "GND")
		)
		(pad "N12" smd circle
			(at 0.40005 1.199896 180)
			(size 0.3556 0.3556)
			(layers "F.Cu" "F.Mask" "F.Paste")
			(net "GND")
		)
		(pad "N13" smd circle
			(at 1.199896 1.199896 180)
			(size 0.3556 0.3556)
			(layers "F.Cu" "F.Mask" "F.Paste")
			(net "GND")
		)
		(pad "N14" smd circle
			(at 1.999996 1.199896 180)
			(size 0.3556 0.3556)
			(layers "F.Cu" "F.Mask" "F.Paste")
			(net "GND")
		)
		(pad "N17" smd circle
			(at 4.400042 1.199896 180)
			(size 0.3556 0.3556)
			(layers "F.Cu" "F.Mask" "F.Paste")
			(net "P3V3_STBY")
		)
		(pad "N18" smd circle
			(at 5.199888 1.199896 180)
			(size 0.3556 0.3556)
			(layers "F.Cu" "F.Mask" "F.Paste")
			(net "ROMA17")
		)
		(pad "N19" smd circle
			(at 5.999988 1.199896 180)
			(size 0.3556 0.3556)
			(layers "F.Cu" "F.Mask" "F.Paste")
			(net "ROMA18")
		)
		(pad "N20" smd circle
			(at 6.800088 1.199896 180)
			(size 0.3556 0.3556)
			(layers "F.Cu" "F.Mask" "F.Paste")
			(net "ROMA21")
		)
		(pad "N21" smd circle
			(at 7.599934 1.199896 180)
			(size 0.3556 0.3556)
			(layers "F.Cu" "F.Mask" "F.Paste")
			(net "GPIOS5_R")
		)
		(pad "N22" smd circle
			(at 8.400034 1.199896 180)
			(size 0.3556 0.3556)
			(layers "F.Cu" "F.Mask" "F.Paste")
			(net "ROMA20")
		)
		(pad "P1" smd circle
			(at -8.400034 1.999996 180)
			(size 0.3556 0.3556)
			(layers "F.Cu" "F.Mask" "F.Paste")
			(net "P3V3_STBY")
		)
		(pad "P2" smd circle
			(at -7.599934 1.999996 180)
			(size 0.3556 0.3556)
			(layers "F.Cu" "F.Mask" "F.Paste")
			(net "ADCVREXT")
		)
		(pad "P3" smd circle
			(at -6.800088 1.999996 180)
			(size 0.3556 0.3556)
			(layers "F.Cu" "F.Mask" "F.Paste")
			(net "ADCAV33")
		)
		(pad "P4" smd circle
			(at -5.999988 1.999996 180)
			(size 0.3556 0.3556)
			(layers "F.Cu" "F.Mask" "F.Paste")
			(net "GND")
		)
		(pad "P5" smd circle
			(at -5.199888 1.999996 180)
			(size 0.3556 0.3556)
			(layers "F.Cu" "F.Mask" "F.Paste")
			(net "GND")
		)
		(pad "P6" smd circle
			(at -4.400042 1.999996 180)
			(size 0.3556 0.3556)
			(layers "F.Cu" "F.Mask" "F.Paste")
			(net "P1V26_STBY")
		)
		(pad "P9" smd circle
			(at -1.999996 1.999996 180)
			(size 0.3556 0.3556)
			(layers "F.Cu" "F.Mask" "F.Paste")
			(net "GND")
		)
		(pad "P10" smd circle
			(at -1.199896 1.999996 180)
			(size 0.3556 0.3556)
			(layers "F.Cu" "F.Mask" "F.Paste")
			(net "GND")
		)
		(pad "P11" smd circle
			(at -0.40005 1.999996 180)
			(size 0.3556 0.3556)
			(layers "F.Cu" "F.Mask" "F.Paste")
			(net "GND")
		)
		(pad "P12" smd circle
			(at 0.40005 1.999996 180)
			(size 0.3556 0.3556)
			(layers "F.Cu" "F.Mask" "F.Paste")
			(net "GND")
		)
		(pad "P13" smd circle
			(at 1.199896 1.999996 180)
			(size 0.3556 0.3556)
			(layers "F.Cu" "F.Mask" "F.Paste")
			(net "GND")
		)
		(pad "P14" smd circle
			(at 1.999996 1.999996 180)
			(size 0.3556 0.3556)
			(layers "F.Cu" "F.Mask" "F.Paste")
			(net "GND")
		)
		(pad "P17" smd circle
			(at 4.400042 1.999996 180)
			(size 0.3556 0.3556)
			(layers "F.Cu" "F.Mask" "F.Paste")
			(net "P1V26_STBY")
		)
		(pad "P18" smd circle
			(at 5.199888 1.999996 180)
			(size 0.3556 0.3556)
			(layers "F.Cu" "F.Mask" "F.Paste")
			(net "ROMA3")
		)
		(pad "P19" smd circle
			(at 5.999988 1.999996 180)
			(size 0.3556 0.3556)
			(layers "F.Cu" "F.Mask" "F.Paste")
			(net "ROMA4")
		)
		(pad "P20" smd circle
			(at 6.800088 1.999996 180)
			(size 0.3556 0.3556)
			(layers "F.Cu" "F.Mask" "F.Paste")
			(net "ROMA5")
		)
		(pad "P21" smd circle
			(at 7.599934 1.999996 180)
			(size 0.3556 0.3556)
			(layers "F.Cu" "F.Mask" "F.Paste")
			(net "ROMA6")
		)
		(pad "P22" smd circle
			(at 8.400034 1.999996 180)
			(size 0.3556 0.3556)
			(layers "F.Cu" "F.Mask" "F.Paste")
			(net "ROMA7")
		)
		(pad "R1" smd circle
			(at -8.400034 2.800096 180)
			(size 0.3556 0.3556)
			(layers "F.Cu" "F.Mask" "F.Paste")
			(net "DACRSET")
		)
		(pad "R2" smd circle
			(at -7.599934 2.800096 180)
			(size 0.3556 0.3556)
			(layers "F.Cu" "F.Mask" "F.Paste")
			(net "DACR")
		)
		(pad "R3" smd circle
			(at -6.800088 2.800096 180)
			(size 0.3556 0.3556)
			(layers "F.Cu" "F.Mask" "F.Paste")
			(net "DACG")
		)
		(pad "R4" smd circle
			(at -5.999988 2.800096 180)
			(size 0.3556 0.3556)
			(layers "F.Cu" "F.Mask" "F.Paste")
			(net "DACB")
		)
		(pad "R5" smd circle
			(at -5.199888 2.800096 180)
			(size 0.3556 0.3556)
			(layers "F.Cu" "F.Mask" "F.Paste")
			(net "GND")
		)
		(pad "R6" smd circle
			(at -4.400042 2.800096 180)
			(size 0.3556 0.3556)
			(layers "F.Cu" "F.Mask" "F.Paste")
			(net "P1V26_STBY")
		)
		(pad "R17" smd circle
			(at 4.400042 2.800096 180)
			(size 0.3556 0.3556)
			(layers "F.Cu" "F.Mask" "F.Paste")
			(net "P1V26_STBY")
		)
		(pad "R18" smd circle
			(at 5.199888 2.800096 180)
			(size 0.3556 0.3556)
			(layers "F.Cu" "F.Mask" "F.Paste")
			(net "TP_GPIOS4")
		)
		(pad "R19" smd circle
			(at 5.999988 2.800096 180)
			(size 0.3556 0.3556)
			(layers "F.Cu" "F.Mask" "F.Paste")
			(net "FLA_CS")
		)
		(pad "R20" smd circle
			(at 6.800088 2.800096 180)
			(size 0.3556 0.3556)
			(layers "F.Cu" "F.Mask" "F.Paste")
			(net "ROMA0")
		)
		(pad "R21" smd circle
			(at 7.599934 2.800096 180)
			(size 0.3556 0.3556)
			(layers "F.Cu" "F.Mask" "F.Paste")
			(net "ROMA1")
		)
		(pad "R22" smd circle
			(at 8.400034 2.800096 180)
			(size 0.3556 0.3556)
			(layers "F.Cu" "F.Mask" "F.Paste")
			(net "ROMA2")
		)
		(pad "T1" smd circle
			(at -8.400034 3.599942 180)
			(size 0.3556 0.3556)
			(layers "F.Cu" "F.Mask" "F.Paste")
			(net "TP_BMC_GPIOJ7")
		)
		(pad "T2" smd circle
			(at -7.599934 3.599942 180)
			(size 0.3556 0.3556)
			(layers "F.Cu" "F.Mask" "F.Paste")
			(net "TP_BMC_GPIOJ6")
		)
		(pad "T3" smd circle
			(at -6.800088 3.599942 180)
			(size 0.3556 0.3556)
			(layers "F.Cu" "F.Mask" "F.Paste")
			(net "P3V3_STBY")
		)
		(pad "T4" smd circle
			(at -5.999988 3.599942 180)
			(size 0.3556 0.3556)
			(layers "F.Cu" "F.Mask" "F.Paste")
			(net "TP_BMC_GPIOJ4")
		)
		(pad "T5" smd circle
			(at -5.199888 3.599942 180)
			(size 0.3556 0.3556)
			(layers "F.Cu" "F.Mask" "F.Paste")
			(net "CBL_PRSNT_N_2")
		)
		(pad "T18" smd circle
			(at 5.199888 3.599942 180)
			(size 0.3556 0.3556)
			(layers "F.Cu" "F.Mask" "F.Paste")
			(net "ROMA16")
		)
		(pad "T19" smd circle
			(at 5.999988 3.599942 180)
			(size 0.3556 0.3556)
			(layers "F.Cu" "F.Mask" "F.Paste")
			(net "ROMD5")
		)
		(pad "T20" smd circle
			(at 6.800088 3.599942 180)
			(size 0.3556 0.3556)
			(layers "F.Cu" "F.Mask" "F.Paste")
			(net "ROMD2")
		)
		(pad "T21" smd circle
			(at 7.599934 3.599942 180)
			(size 0.3556 0.3556)
			(layers "F.Cu" "F.Mask" "F.Paste")
			(net "ROMD1")
		)
		(pad "T22" smd circle
			(at 8.400034 3.599942 180)
			(size 0.3556 0.3556)
			(layers "F.Cu" "F.Mask" "F.Paste")
			(net "ROMD0")
		)
		(pad "U1" smd circle
			(at -8.400034 4.400042 180)
			(size 0.3556 0.3556)
			(layers "F.Cu" "F.Mask" "F.Paste")
			(net "CBL_PRSNT_N_1")
		)
		(pad "U2" smd circle
			(at -7.599934 4.400042 180)
			(size 0.3556 0.3556)
			(layers "F.Cu" "F.Mask" "F.Paste")
			(net "TP_BMC_GPIOJ5")
		)
		(pad "U3" smd circle
			(at -6.800088 4.400042 180)
			(size 0.3556 0.3556)
			(layers "F.Cu" "F.Mask" "F.Paste")
			(net "CBL_PRSNT_N_3")
		)
		(pad "U4" smd circle
			(at -5.999988 4.400042 180)
			(size 0.3556 0.3556)
			(layers "F.Cu" "F.Mask" "F.Paste")
			(net "CBL_PRSNT_N_5")
		)
		(pad "U5" smd circle
			(at -5.199888 4.400042 180)
			(size 0.3556 0.3556)
			(layers "F.Cu" "F.Mask" "F.Paste")
			(net "CBL_PRSNT_N_8")
		)
		(pad "U8" smd circle
			(at -2.800096 4.400042 180)
			(size 0.3556 0.3556)
			(layers "F.Cu" "F.Mask" "F.Paste")
			(net "P3V3_STBY")
		)
		(pad "U9" smd circle
			(at -1.999996 4.400042 180)
			(size 0.3556 0.3556)
			(layers "F.Cu" "F.Mask" "F.Paste")
			(net "P3V3_STBY")
		)
		(pad "U10" smd circle
			(at -1.199896 4.400042 180)
			(size 0.3556 0.3556)
			(layers "F.Cu" "F.Mask" "F.Paste")
			(net "P1V53_STBY")
		)
		(pad "U11" smd circle
			(at -0.40005 4.400042 180)
			(size 0.3556 0.3556)
			(layers "F.Cu" "F.Mask" "F.Paste")
			(net "P1V53_STBY")
		)
		(pad "U12" smd circle
			(at 0.40005 4.400042 180)
			(size 0.3556 0.3556)
			(layers "F.Cu" "F.Mask" "F.Paste")
			(net "P1V26_STBY")
		)
		(pad "U13" smd circle
			(at 1.199896 4.400042 180)
			(size 0.3556 0.3556)
			(layers "F.Cu" "F.Mask" "F.Paste")
			(net "P1V26_STBY")
		)
		(pad "U14" smd circle
			(at 1.999996 4.400042 180)
			(size 0.3556 0.3556)
			(layers "F.Cu" "F.Mask" "F.Paste")
			(net "P1V53_STBY")
		)
		(pad "U15" smd circle
			(at 2.800096 4.400042 180)
			(size 0.3556 0.3556)
			(layers "F.Cu" "F.Mask" "F.Paste")
			(net "P1V53_STBY")
		)
		(pad "U18" smd circle
			(at 5.199888 4.400042 180)
			(size 0.3556 0.3556)
			(layers "F.Cu" "F.Mask" "F.Paste")
			(net "EXP_TRAY_ID_BMC")
		)
		(pad "U19" smd circle
			(at 5.999988 4.400042 180)
			(size 0.3556 0.3556)
			(layers "F.Cu" "F.Mask" "F.Paste")
			(net "GPIOR3_R")
		)
		(pad "U20" smd circle
			(at 6.800088 4.400042 180)
			(size 0.3556 0.3556)
			(layers "F.Cu" "F.Mask" "F.Paste")
			(net "ROMD7")
		)
		(pad "U21" smd circle
			(at 7.599934 4.400042 180)
			(size 0.3556 0.3556)
			(layers "F.Cu" "F.Mask" "F.Paste")
			(net "ROMD4")
		)
		(pad "U22" smd circle
			(at 8.400034 4.400042 180)
			(size 0.3556 0.3556)
			(layers "F.Cu" "F.Mask" "F.Paste")
			(net "ROMD3")
		)
		(pad "V1" smd circle
			(at -8.400034 5.199888 180)
			(size 0.3556 0.3556)
			(layers "F.Cu" "F.Mask" "F.Paste")
			(net "CBL_PRSNT_N_4")
		)
		(pad "V2" smd circle
			(at -7.599934 5.199888 180)
			(size 0.3556 0.3556)
			(layers "F.Cu" "F.Mask" "F.Paste")
			(net "CBL_PRSNT_N_6")
		)
		(pad "V3" smd circle
			(at -6.800088 5.199888 180)
			(size 0.3556 0.3556)
			(layers "F.Cu" "F.Mask" "F.Paste")
			(net "GPIOM0_I210_PERST_N")
		)
		(pad "V4" smd circle
			(at -5.999988 5.199888 180)
			(size 0.3556 0.3556)
			(layers "F.Cu" "F.Mask" "F.Paste")
			(net "BMC_SSD_RST#2")
		)
	)
)
